(kicad_pcb
	(version 20260206)
	(generator "pcbnew")
	(generator_version "10.0")
	(general
		(thickness 1.6)
		(legacy_teardrops no)
	)
	(paper "A4")
	(title_block
		(title "Bryce Canyon_R.DPB_16317-1_OCP.brd")
		(comment 1 "Bryce Canyon / footprints 1785-1788 of 2099")
	)
	(layers
		(0 "F.Cu" signal "TOP")
		(4 "In1.Cu" signal "L2GND")
		(6 "In2.Cu" signal "L3")
		(8 "In3.Cu" signal "L4VCC")
		(10 "In4.Cu" signal "L5VCC")
		(12 "In5.Cu" signal "L6")
		(14 "In6.Cu" signal "L7GND")
		(2 "B.Cu" signal "BOTTOM")
		(9 "F.Adhes" user "F.Adhesive")
		(11 "B.Adhes" user "B.Adhesive")
		(13 "F.Paste" user "Package Geometry/Pastemask Top")
		(15 "B.Paste" user "Package Geometry/Pastemask Bottom")
		(5 "F.SilkS" user "Ref Des/Silkscreen Top")
		(7 "B.SilkS" user "Ref Des/Silkscreen Bottom")
		(1 "F.Mask" user "Board Geometry/Soldermask Top")
		(3 "B.Mask" user "Board Geometry/Soldermask Bottom")
		(17 "Dwgs.User" user "User.Drawings")
		(19 "Cmts.User" user "User.Comments")
		(21 "Eco1.User" user "User.Eco1")
		(23 "Eco2.User" user "User.Eco2")
		(25 "Edge.Cuts" user "Board Geometry/Outline")
		(27 "Margin" user)
		(31 "F.CrtYd" user "Package Geometry/Place Bound Top")
		(29 "B.CrtYd" user "Package Geometry/Place Bound Bottom")
		(35 "F.Fab" user "Ref Des/Assembly Top")
		(33 "B.Fab" user "Ref Des/Assembly Bottom")
	)
	(footprint ""
		(layer "F.Cu")
		(at 459.74 -40.5638 -90)
		(property "Reference" "R853"
			(at 0 0 270)
			(layer "F.SilkS")
			(hide yes)
			(effects
				(font
					(size 1.27 1.27)
				)
			)
		)
		(property "Value" "2R6F-GP"
			(at -0.0508 -4.8514 270)
			(unlocked yes)
			(layer "F.Fab")
			(hide yes)
			(effects
				(font
					(size 1.016 1.016)
					(thickness 0.1524)
				)
			)
		)
		(property "Device Type" "R1206H26"
			(at 0 -6.3754 270)
			(unlocked yes)
			(layer "F.Fab")
			(hide yes)
			(effects
				(font
					(size 1.016 1.016)
					(thickness 0.1524)
				)
			)
		)
		(duplicate_pad_numbers_are_jumpers no)
		(fp_line
			(start -1.016 2.2352)
			(end -1.016 -2.2352)
			(stroke
				(width 0.1524)
				(type default)
			)
			(layer "F.SilkS")
		)
		(fp_line
			(start 1.016 2.2352)
			(end -1.016 2.2352)
			(stroke
				(width 0.1524)
				(type default)
			)
			(layer "F.SilkS")
		)
		(fp_line
			(start -1.016 -2.2352)
			(end 1.016 -2.2352)
			(stroke
				(width 0.1524)
				(type default)
			)
			(layer "F.SilkS")
		)
		(fp_line
			(start 1.016 -2.2352)
			(end 1.016 2.2352)
			(stroke
				(width 0.1524)
				(type default)
			)
			(layer "F.SilkS")
		)
		(fp_rect
			(start -1.0922 2.3114)
			(end 1.0922 -2.3114)
			(stroke
				(width 0)
				(type default)
			)
			(fill no)
			(layer "F.CrtYd")
		)
		(fp_poly
			(pts
				(xy -1.0922 -2.3114) (xy 1.0922 -2.3114) (xy 1.0922 2.3114) (xy -1.0922 2.3114)
			)
			(stroke
				(width 0)
				(type default)
			)
			(fill no)
			(layer "F.Fab")
		)
		(pad "1" smd rect
			(at 0 -1.397 270)
			(size 1.651 1.27)
			(layers "F.Cu" "F.Mask" "F.Paste")
			(net "P12V_HDD34")
		)
		(pad "2" smd rect
			(at 0 1.397 270)
			(size 1.651 1.27)
			(layers "F.Cu" "F.Mask" "F.Paste")
			(net "12V_PRE_34")
		)
	)
	(footprint ""
		(layer "F.Cu")
		(at 459.806802 -224.31375)
		(property "Reference" "R1139"
			(at 0 0 0)
			(layer "F.SilkS")
			(hide yes)
			(effects
				(font
					(size 1.27 1.27)
				)
			)
		)
		(property "Value" "0R3J-0-U-GP"
			(at -0.0254 -2.5146 0)
			(unlocked yes)
			(layer "F.Fab")
			(hide yes)
			(effects
				(font
					(size 1.016 1.016)
					(thickness 0.1524)
				)
			)
		)
		(property "Device Type" "R603H22"
			(at -0.0254 -4.0386 0)
			(unlocked yes)
			(layer "F.Fab")
			(hide yes)
			(effects
				(font
					(size 1.016 1.016)
					(thickness 0.1524)
				)
			)
		)
		(duplicate_pad_numbers_are_jumpers no)
		(fp_line
			(start -0.4826 0)
			(end -0.2032 0)
			(stroke
				(width 0.2032)
				(type default)
			)
			(layer "F.SilkS")
		)
		(fp_line
			(start 0.2032 0)
			(end 0.4826 0)
			(stroke
				(width 0.2032)
				(type default)
			)
			(layer "F.SilkS")
		)
		(fp_rect
			(start -0.5842 1.3335)
			(end 0.5842 -1.3335)
			(stroke
				(width 0)
				(type default)
			)
			(fill no)
			(layer "F.CrtYd")
		)
		(fp_rect
			(start -0.5842 1.3335)
			(end 0.5842 -1.3335)
			(stroke
				(width 0)
				(type default)
			)
			(fill no)
			(layer "F.Fab")
		)
		(pad "1" smd custom
			(at 0 -0.762)
			(size 0.2159 0.2159)
			(layers "F.Cu" "F.Mask" "F.Paste")
			(net "P5V_B_3_VBST")
			(options
				(clearance outline)
				(anchor circle)
			)
			(primitives
				(gr_poly
					(pts
						(arc
							(start -0.3302 -0.4318)
							(mid -0.402042 -0.402042)
							(end -0.4318 -0.3302)
						)
						(arc
							(start -0.4318 0.3302)
							(mid -0.402042 0.402042)
							(end -0.3302 0.4318)
						)
						(arc
							(start 0.3302 0.4318)
							(mid 0.402042 0.402042)
							(end 0.4318 0.3302)
						)
						(arc
							(start 0.4318 -0.3302)
							(mid 0.402042 -0.402042)
							(end 0.3302 -0.4318)
						)
					)
					(width 0)
					(fill yes)
				)
			)
		)
		(pad "2" smd custom
			(at 0 0.762)
			(size 0.2159 0.2159)
			(layers "F.Cu" "F.Mask" "F.Paste")
			(net "P5V_B_3_VBST_RC")
			(options
				(clearance outline)
				(anchor circle)
			)
			(primitives
				(gr_poly
					(pts
						(arc
							(start -0.3302 -0.4318)
							(mid -0.402042 -0.402042)
							(end -0.4318 -0.3302)
						)
						(arc
							(start -0.4318 0.3302)
							(mid -0.402042 0.402042)
							(end -0.3302 0.4318)
						)
						(arc
							(start 0.3302 0.4318)
							(mid 0.402042 0.402042)
							(end 0.4318 0.3302)
						)
						(arc
							(start 0.4318 -0.3302)
							(mid 0.402042 -0.402042)
							(end 0.3302 -0.4318)
						)
					)
					(width 0)
					(fill yes)
				)
			)
		)
	)
	(footprint ""
		(layer "F.Cu")
		(at 91.300046 -143.91005 -90)
		(property "Reference" "HDDSAS14"
			(at 0 0 270)
			(layer "F.SilkS")
			(hide yes)
			(effects
				(font
					(size 1.27 1.27)
				)
			)
		)
		(property "Value" "SKT-SAS15P-14P-45-GP"
			(at -20.7645 -8.9789 270)
			(unlocked yes)
			(layer "F.Fab")
			(hide yes)
			(effects
				(font
					(size 1.016 1.016)
					(thickness 0.1524)
				)
			)
		)
		(property "Device Type" "10120818-001C-TRLF"
			(at -20.7645 -10.5029 270)
			(unlocked yes)
			(layer "F.Fab")
			(hide yes)
			(effects
				(font
					(size 1.016 1.016)
					(thickness 0.1524)
				)
			)
		)
		(duplicate_pad_numbers_are_jumpers no)
		(fp_line
			(start 1.651 4.2926)
			(end 1.651 3.0099)
			(stroke
				(width 0.1524)
				(type default)
			)
			(layer "F.SilkS")
		)
		(fp_line
			(start 8.509 4.2926)
			(end 1.651 4.2926)
			(stroke
				(width 0.1524)
				(type default)
			)
			(layer "F.SilkS")
		)
		(fp_line
			(start -23.4188 3.0099)
			(end -23.4188 -3.2512)
			(stroke
				(width 0.1524)
				(type default)
			)
			(layer "F.SilkS")
		)
		(fp_line
			(start 1.651 3.0099)
			(end -23.4188 3.0099)
			(stroke
				(width 0.1524)
				(type default)
			)
			(layer "F.SilkS")
		)
		(fp_line
			(start 8.509 3.0099)
			(end 8.509 4.2926)
			(stroke
				(width 0.1524)
				(type default)
			)
			(layer "F.SilkS")
		)
		(fp_line
			(start 23.4188 3.0099)
			(end 8.509 3.0099)
			(stroke
				(width 0.1524)
				(type default)
			)
			(layer "F.SilkS")
		)
		(fp_line
			(start -23.4188 -3.2512)
			(end 23.4188 -3.2512)
			(stroke
				(width 0.1524)
				(type default)
			)
			(layer "F.SilkS")
		)
		(fp_line
			(start 23.4188 -3.2512)
			(end 23.4188 3.0099)
			(stroke
				(width 0.1524)
				(type default)
			)
			(layer "F.SilkS")
		)
		(fp_line
			(start 15.5067 -3.3401)
			(end 16.2687 -3.3401)
			(stroke
				(width 0.3302)
				(type default)
			)
			(layer "F.SilkS")
		)
		(fp_poly
			(pts
				(xy 15.868904 -3.230372) (xy 16.503904 -3.865372) (xy 15.233904 -3.865372)
			)
			(stroke
				(width 0)
				(type default)
			)
			(fill yes)
			(layer "F.SilkS")
		)
		(fp_poly
			(pts
				(xy -22.8727 -2.7559) (xy 22.8727 -2.7559) (xy 22.8727 2.7559) (xy 8.255 2.7559) (xy 8.255 3.5179)
				(xy 1.905 3.5179) (xy 1.905 2.7559) (xy -22.8727 2.7559)
			)
			(stroke
				(width 0)
				(type default)
			)
			(fill no)
			(layer "F.CrtYd")
		)
		(fp_poly
			(pts
				(xy 1.397 4.5466) (xy 1.397 3.2639) (xy -23.6728 3.2639) (xy -23.6728 -3.5052) (xy 23.6728 -3.5052)
				(xy 23.6728 -0.00635) (xy 22.8727 -0.00635) (xy 22.8727 -2.7559) (xy -22.8727 -2.7559) (xy -22.8727 2.7559)
				(xy 1.905 2.7559) (xy 1.905 3.5179) (xy 8.255 3.5179) (xy 8.255 2.7559) (xy 22.8727 2.7559) (xy 22.8727 0.00635)
				(xy 23.6728 0.00635) (xy 23.6728 3.2639) (xy 8.763 3.2639) (xy 8.763 4.5466)
			)
			(stroke
				(width 0)
				(type default)
			)
			(fill no)
			(layer "F.CrtYd")
		)
		(fp_poly
			(pts
				(xy 1.397 4.5466) (xy 1.397 3.2639) (xy -23.6728 3.2639) (xy -23.6728 -3.5052) (xy 23.6728 -3.5052)
				(xy 23.6728 3.2639) (xy 8.763 3.2639) (xy 8.763 4.5466)
			)
			(stroke
				(width 0)
				(type default)
			)
			(fill no)
			(layer "F.Fab")
		)
		(pad "" np_thru_hole circle
			(at -18.874994 0 270)
			(size 0.254 0.254)
			(drill 1.3462)
			(layers "*.Cu" "*.Mask")
			(clearance 0.9017)
			(thermal_gap 0.9017)
		)
		(pad "" np_thru_hole circle
			(at 18.874994 0 270)
			(size 0.254 0.254)
			(drill 0.9398)
			(layers "*.Cu" "*.Mask")
			(clearance 0.6985)
			(thermal_gap 0.6985)
		)
		(pad "G1" smd rect
			(at 21.874988 0 270)
			(size 2.5908 2.5908)
			(layers "F.Cu" "F.Mask" "F.Paste")
			(net "GND")
		)
		(pad "G2" smd rect
			(at -21.874988 0 270)
			(size 2.5908 2.5908)
			(layers "F.Cu" "F.Mask" "F.Paste")
			(net "GND")
		)
		(pad "P1" smd rect
			(at 1.905 -1.82499 270)
			(size 0.6096 2.3622)
			(layers "F.Cu" "F.Mask" "F.Paste")
			(net "Net_1734")
		)
		(pad "P2" smd rect
			(at 0.635 -1.82499 270)
			(size 0.6096 2.3622)
			(layers "F.Cu" "F.Mask" "F.Paste")
			(net "Net_1735")
		)
		(pad "P3" smd rect
			(at -0.635 -1.82499 270)
			(size 0.6096 2.3622)
			(layers "F.Cu" "F.Mask" "F.Paste")
			(net "Net_1736")
		)
		(pad "P4" smd rect
			(at -1.905 -1.82499 270)
			(size 0.6096 2.3622)
			(layers "F.Cu" "F.Mask" "F.Paste")
			(net "GND")
		)
		(pad "P5" smd rect
			(at -3.175 -1.82499 270)
			(size 0.6096 2.3622)
			(layers "F.Cu" "F.Mask" "F.Paste")
			(net "HDD_PRSNT_14")
		)
		(pad "P6" smd rect
			(at -4.445 -1.82499 270)
			(size 0.6096 2.3622)
			(layers "F.Cu" "F.Mask" "F.Paste")
			(net "GND")
		)
		(pad "P7" smd rect
			(at -5.715 -1.82499 270)
			(size 0.6096 2.3622)
			(layers "F.Cu" "F.Mask" "F.Paste")
			(net "5V_PRE_14")
		)
		(pad "P8" smd rect
			(at -6.985 -1.82499 270)
			(size 0.6096 2.3622)
			(layers "F.Cu" "F.Mask" "F.Paste")
			(net "P5V_HDD14")
		)
		(pad "P9" smd rect
			(at -8.255 -1.82499 270)
			(size 0.6096 2.3622)
			(layers "F.Cu" "F.Mask" "F.Paste")
			(net "P5V_HDD14")
		)
		(pad "P10" smd rect
			(at -9.525 -1.82499 270)
			(size 0.6096 2.3622)
			(layers "F.Cu" "F.Mask" "F.Paste")
			(net "GND")
		)
		(pad "P11" smd rect
			(at -10.795 -1.82499 270)
			(size 0.6096 2.3622)
			(layers "F.Cu" "F.Mask" "F.Paste")
			(net "ACT_HDD_14")
		)
		(pad "P12" smd rect
			(at -12.065 -1.82499 270)
			(size 0.6096 2.3622)
			(layers "F.Cu" "F.Mask" "F.Paste")
			(net "GND")
		)
		(pad "P13" smd rect
			(at -13.335 -1.82499 270)
			(size 0.6096 2.3622)
			(layers "F.Cu" "F.Mask" "F.Paste")
			(net "12V_PRE_14")
		)
		(pad "P14" smd rect
			(at -14.605 -1.82499 270)
			(size 0.6096 2.3622)
			(layers "F.Cu" "F.Mask" "F.Paste")
			(net "P12V_HDD14")
		)
		(pad "P15" smd rect
			(at -15.875 -1.82499 270)
			(size 0.6096 2.3622)
			(layers "F.Cu" "F.Mask" "F.Paste")
			(net "P12V_HDD14")
		)
		(pad "S1" smd rect
			(at 15.875 -1.82499 270)
			(size 0.6096 2.3622)
			(layers "F.Cu" "F.Mask" "F.Paste")
			(net "GND")
		)
		(pad "S2" smd rect
			(at 14.605 -1.82499 270)
			(size 0.6096 2.3622)
			(layers "F.Cu" "F.Mask" "F.Paste")
			(net "SAS_HDD_RX_P14")
		)
		(pad "S3" smd rect
			(at 13.335 -1.82499 270)
			(size 0.6096 2.3622)
			(layers "F.Cu" "F.Mask" "F.Paste")
			(net "SAS_HDD_RX_N14")
		)
		(pad "S4" smd rect
			(at 12.065 -1.82499 270)
			(size 0.6096 2.3622)
			(layers "F.Cu" "F.Mask" "F.Paste")
			(net "GND")
		)
		(pad "S5" smd rect
			(at 10.795 -1.82499 270)
			(size 0.6096 2.3622)
			(layers "F.Cu" "F.Mask" "F.Paste")
			(net "PHY_DRV_B_TO_SCC_B_14_DN")
		)
		(pad "S6" smd rect
			(at 9.525 -1.82499 270)
			(size 0.6096 2.3622)
			(layers "F.Cu" "F.Mask" "F.Paste")
			(net "PHY_DRV_B_TO_SCC_B_14_DP")
		)
		(pad "S7" smd rect
			(at 8.255 -1.82499 270)
			(size 0.6096 2.3622)
			(layers "F.Cu" "F.Mask" "F.Paste")
			(net "GND")
		)
		(pad "S8" smd rect
			(at 7.480046 2.845054 270)
			(size 0.508 2.3622)
			(layers "F.Cu" "F.Mask" "F.Paste")
			(net "GND")
		)
		(pad "S9" smd rect
			(at 6.679946 2.845054 270)
			(size 0.508 2.3622)
			(layers "F.Cu" "F.Mask" "F.Paste")
			(net "Net_437")
		)
		(pad "S10" smd rect
			(at 5.8801 2.845054 270)
			(size 0.508 2.3622)
			(layers "F.Cu" "F.Mask" "F.Paste")
			(net "Net_329")
		)
		(pad "S11" smd rect
			(at 5.08 2.845054 270)
			(size 0.508 2.3622)
			(layers "F.Cu" "F.Mask" "F.Paste")
			(net "GND")
		)
		(pad "S12" smd rect
			(at 4.2799 2.845054 270)
			(size 0.508 2.3622)
			(layers "F.Cu" "F.Mask" "F.Paste")
			(net "Net_365")
		)
		(pad "S13" smd rect
			(at 3.480054 2.845054 270)
			(size 0.508 2.3622)
			(layers "F.Cu" "F.Mask" "F.Paste")
			(net "Net_401")
		)
		(pad "S14" smd rect
			(at 2.679954 2.845054 270)
			(size 0.508 2.3622)
			(layers "F.Cu" "F.Mask" "F.Paste")
			(net "GND")
		)
		(zone
			(layer "F.Cu")
			(hatch none 0.5)
			(connect_pads
				(clearance 0)
			)
			(min_thickness 0.25)
			(keepout
				(tracks allowed)
				(vias not_allowed)
				(pads allowed)
				(copperpour not_allowed)
				(footprints allowed)
			)
			(placement
				(enabled no)
				(sheetname "")
			)
			(fill
				(thermal_gap 0.5)
				(thermal_bridge_width 0.5)
				(island_removal_mode 0)
			)
			(polygon
				(pts
					(xy 94.957646 -160.64865) (xy 87.883746 -160.64865) (xy 87.883746 -167.58285) (xy 88.988646 -167.58285)
					(xy 88.988646 -163.46805) (xy 93.611446 -163.46805) (xy 93.611446 -167.58285) (xy 94.957646 -167.58285)
				)
			)
		)
		(zone
			(layer "F.Cu")
			(hatch none 0.5)
			(connect_pads
				(clearance 0)
			)
			(min_thickness 0.25)
			(keepout
				(tracks not_allowed)
				(vias allowed)
				(pads allowed)
				(copperpour not_allowed)
				(footprints allowed)
			)
			(placement
				(enabled no)
				(sheetname "")
			)
			(fill
				(thermal_gap 0.5)
				(thermal_bridge_width 0.5)
				(island_removal_mode 0)
			)
			(polygon
				(pts
					(xy 94.957646 -160.64865) (xy 87.883746 -160.64865) (xy 87.883746 -167.58285) (xy 88.988646 -167.58285)
					(xy 88.988646 -163.46805) (xy 93.611446 -163.46805) (xy 93.611446 -167.58285) (xy 94.957646 -167.58285)
				)
			)
		)
		(zone
			(layer "F.Cu")
			(hatch none 0.5)
			(connect_pads
				(clearance 0)
			)
			(min_thickness 0.25)
			(keepout
				(tracks not_allowed)
				(vias allowed)
				(pads allowed)
				(copperpour not_allowed)
				(footprints allowed)
			)
			(placement
				(enabled no)
				(sheetname "")
			)
			(fill
				(thermal_gap 0.5)
				(thermal_bridge_width 0.5)
				(island_removal_mode 0)
			)
			(polygon
				(pts
					(xy 94.957646 -127.17145) (xy 87.883746 -127.17145) (xy 87.883746 -120.23725) (xy 88.988646 -120.23725)
					(xy 88.988646 -124.35205) (xy 93.611446 -124.35205) (xy 93.611446 -120.23725) (xy 94.957646 -120.23725)
				)
			)
		)
		(zone
			(layer "F.Cu")
			(hatch none 0.5)
			(connect_pads
				(clearance 0)
			)
			(min_thickness 0.25)
			(keepout
				(tracks allowed)
				(vias not_allowed)
				(pads allowed)
				(copperpour not_allowed)
				(footprints allowed)
			)
			(placement
				(enabled no)
				(sheetname "")
			)
			(fill
				(thermal_gap 0.5)
				(thermal_bridge_width 0.5)
				(island_removal_mode 0)
			)
			(polygon
				(pts
					(xy 94.957646 -127.17145) (xy 87.883746 -127.17145) (xy 87.883746 -120.23725) (xy 88.988646 -120.23725)
					(xy 88.988646 -124.35205) (xy 93.611446 -124.35205) (xy 93.611446 -120.23725) (xy 94.957646 -120.23725)
				)
			)
		)
		(zone
			(layers "F.Cu" "B.Cu" "In1.Cu" "In2.Cu" "In3.Cu" "In4.Cu" "In5.Cu" "In6.Cu")
			(hatch none 0.5)
			(connect_pads
				(clearance 0)
			)
			(min_thickness 0.25)
			(keepout
				(tracks not_allowed)
				(vias allowed)
				(pads allowed)
				(copperpour not_allowed)
				(footprints allowed)
			)
			(placement
				(enabled no)
				(sheetname "")
			)
			(fill
				(thermal_gap 0.5)
				(thermal_bridge_width 0.5)
				(island_removal_mode 0)
			)
			(polygon
				(pts
					(arc
						(start 92.074746 -125.035056)
						(mid 90.525346 -125.035056)
						(end 92.074746 -125.035056)
					)
				)
			)
		)
		(zone
			(layers "F.Cu" "B.Cu" "In1.Cu" "In2.Cu" "In3.Cu" "In4.Cu" "In5.Cu" "In6.Cu")
			(hatch none 0.5)
			(connect_pads
				(clearance 0)
			)
			(min_thickness 0.25)
			(keepout
				(tracks not_allowed)
				(vias allowed)
				(pads allowed)
				(copperpour not_allowed)
				(footprints allowed)
			)
			(placement
				(enabled no)
				(sheetname "")
			)
			(fill
				(thermal_gap 0.5)
				(thermal_bridge_width 0.5)
				(island_removal_mode 0)
			)
			(polygon
				(pts
					(arc
						(start 92.277946 -162.785044)
						(mid 90.322146 -162.785044)
						(end 92.277946 -162.785044)
					)
				)
			)
		)
	)
	(footprint ""
		(layer "F.Cu")
		(at 83.2866 -263.779 -90)
		(property "Reference" "C56"
			(at 0 0 270)
			(layer "F.SilkS")
			(hide yes)
			(effects
				(font
					(size 1.27 1.27)
				)
			)
		)
		(property "Value" "SC1U16V3KX-5GP"
			(at 0 -2.8194 270)
			(unlocked yes)
			(layer "F.Fab")
			(hide yes)
			(effects
				(font
					(size 1.016 1.016)
					(thickness 0.1524)
				)
			)
		)
		(property "Device Type" "C603H36"
			(at 0 -4.3434 270)
			(unlocked yes)
			(layer "F.Fab")
			(hide yes)
			(effects
				(font
					(size 1.016 1.016)
					(thickness 0.1524)
				)
			)
		)
		(duplicate_pad_numbers_are_jumpers no)
		(fp_line
			(start 0.508 0)
			(end -0.508 0)
			(stroke
				(width 0.2032)
				(type default)
			)
			(layer "F.SilkS")
		)
		(fp_rect
			(start -0.5842 1.3335)
			(end 0.5842 -1.3335)
			(stroke
				(width 0)
				(type default)
			)
			(fill no)
			(layer "F.CrtYd")
		)
		(fp_rect
			(start -0.5842 1.3335)
			(end 0.5842 -1.3335)
			(stroke
				(width 0)
				(type default)
			)
			(fill no)
			(layer "F.Fab")
		)
		(pad "1" smd custom
			(at 0 -0.762 270)
			(size 0.2159 0.2159)
			(layers "F.Cu" "F.Mask" "F.Paste")
			(net "P5V_HDD2")
			(options
				(clearance outline)
				(anchor circle)
			)
			(primitives
				(gr_poly
					(pts
						(arc
							(start -0.3302 -0.4318)
							(mid -0.402042 -0.402042)
							(end -0.4318 -0.3302)
						)
						(arc
							(start -0.4318 0.3302)
							(mid -0.402042 0.402042)
							(end -0.3302 0.4318)
						)
						(arc
							(start 0.3302 0.4318)
							(mid 0.402042 0.402042)
							(end 0.4318 0.3302)
						)
						(arc
							(start 0.4318 -0.3302)
							(mid 0.402042 -0.402042)
							(end 0.3302 -0.4318)
						)
					)
					(width 0)
					(fill yes)
				)
			)
		)
		(pad "2" smd custom
			(at 0 0.762 270)
			(size 0.2159 0.2159)
			(layers "F.Cu" "F.Mask" "F.Paste")
			(net "GND")
			(options
				(clearance outline)
				(anchor circle)
			)
			(primitives
				(gr_poly
					(pts
						(arc
							(start -0.3302 -0.4318)
							(mid -0.402042 -0.402042)
							(end -0.4318 -0.3302)
						)
						(arc
							(start -0.4318 0.3302)
							(mid -0.402042 0.402042)
							(end -0.3302 0.4318)
						)
						(arc
							(start 0.3302 0.4318)
							(mid 0.402042 0.402042)
							(end 0.4318 0.3302)
						)
						(arc
							(start 0.4318 -0.3302)
							(mid 0.402042 -0.402042)
							(end 0.3302 -0.4318)
						)
					)
					(width 0)
					(fill yes)
				)
			)
		)
	)
)
